# BASEBOARD_FAB2 (Tioga Pass) — schematic netlist excerpt (pin names and nets, part order shuffled) for the footprints in the layout excerpt that follows; sources: Cadence DE-HDL packaged netlist, KiCad conversion of Wiwynn_Tioga_Pass_MB.brd

C2L38  CAP_A  0.01UF 25V 10% X7R  pkg 0402V  page 173 : A = SATA6G_P6_TX_C_DN ; B = SATA6G_PCH_PCIE_UP_SATA_TXN<6>
R6U3  RES  1.0M 1% EMPTY  pkg 0402  page 229 : A = P3V3 ; B = FM_PVTT_GHJ_EN_R
R3U6  RES  0.0 5% CHIP  pkg 0402  page 216 : A = VR_PVDDQ_ABC_PH1_VCIN ; B = P5V_STBY

(kicad_pcb
	(version 20260206)
	(generator "pcbnew")
	(generator_version "10.0")
	(general
		(thickness 1.6)
		(legacy_teardrops no)
	)
	(paper "A4")
	(title_block
		(title "Wiwynn_Tioga_Pass_MB.brd")
		(comment 1 "Tioga Pass / footprints 4654-4656 of 4770")
	)
	(layers
		(0 "F.Cu" signal "TOP")
		(4 "In1.Cu" signal "L2GND")
		(6 "In2.Cu" signal "L3")
		(8 "In3.Cu" signal "L4GND")
		(10 "In4.Cu" signal "L5")
		(12 "In5.Cu" signal "L6GND")
		(14 "In6.Cu" signal "L7VCC")
		(16 "In7.Cu" signal "L8VCC")
		(18 "In8.Cu" signal "L9GND")
		(20 "In9.Cu" signal "L10")
		(22 "In10.Cu" signal "L11GND")
		(24 "In11.Cu" signal "L12")
		(26 "In12.Cu" signal "L13GND")
		(2 "B.Cu" signal "BOTTOM")
		(9 "F.Adhes" user "F.Adhesive")
		(11 "B.Adhes" user "B.Adhesive")
		(13 "F.Paste" user "Package Geometry/Pastemask Top")
		(15 "B.Paste" user "Package Geometry/Pastemask Bottom")
		(5 "F.SilkS" user "Ref Des/Silkscreen Top")
		(7 "B.SilkS" user "Ref Des/Silkscreen Bottom")
		(1 "F.Mask" user "Board Geometry/Soldermask Top")
		(3 "B.Mask" user "Board Geometry/Soldermask Bottom")
		(17 "Dwgs.User" user "User.Drawings")
		(19 "Cmts.User" user "User.Comments")
		(21 "Eco1.User" user "User.Eco1")
		(23 "Eco2.User" user "User.Eco2")
		(25 "Edge.Cuts" user "Board Geometry/Outline")
		(27 "Margin" user)
		(31 "F.CrtYd" user "Package Geometry/Place Bound Top")
		(29 "B.CrtYd" user "Package Geometry/Place Bound Bottom")
		(35 "F.Fab" user "Ref Des/Assembly Top")
		(33 "B.Fab" user "Ref Des/Assembly Bottom")
	)
	(footprint ""
		(layer "B.Cu")
		(at 348.2086 -8.8138 -90)
		(property "Reference" "R3U6"
			(at 0 0 90)
			(layer "B.SilkS")
			(hide yes)
			(effects
				(font
					(size 1.27 1.27)
				)
				(justify mirror)
			)
		)
		(property "Value" ""
			(at 0 0 90)
			(layer "B.Fab")
			(effects
				(font
					(size 1.27 1.27)
				)
				(justify mirror)
			)
		)
		(duplicate_pad_numbers_are_jumpers no)
		(fp_rect
			(start -0.2794 0.9906)
			(end 0.2794 -0.1016)
			(stroke
				(width 0)
				(type default)
			)
			(fill no)
			(layer "B.CrtYd")
		)
		(fp_line
			(start -0.2794 0.9906)
			(end -0.2794 -0.1016)
			(stroke
				(width 0.1)
				(type default)
			)
			(layer "B.Fab")
		)
		(fp_line
			(start 0.2794 0.9906)
			(end -0.2794 0.9906)
			(stroke
				(width 0.1)
				(type default)
			)
			(layer "B.Fab")
		)
		(fp_line
			(start -0.2794 -0.1016)
			(end 0.2794 -0.1016)
			(stroke
				(width 0.1)
				(type default)
			)
			(layer "B.Fab")
		)
		(fp_line
			(start 0.2794 -0.1016)
			(end 0.2794 0.9906)
			(stroke
				(width 0.1)
				(type default)
			)
			(layer "B.Fab")
		)
		(pad "1" smd rect
			(at 0 0 90)
			(size 0.508 0.508)
			(layers "B.Cu" "B.Mask" "B.Paste")
			(net "VR_PVDDQ_ABC_PH1_VCIN")
		)
		(pad "2" smd rect
			(at 0 0.889 90)
			(size 0.508 0.508)
			(layers "B.Cu" "B.Mask" "B.Paste")
			(net "P5V_STBY")
		)
		(zone
			(layer "B.Cu")
			(hatch none 0.5)
			(connect_pads
				(clearance 0)
			)
			(min_thickness 0.25)
			(keepout
				(tracks not_allowed)
				(vias allowed)
				(pads allowed)
				(copperpour not_allowed)
				(footprints allowed)
			)
			(placement
				(enabled no)
				(sheetname "")
			)
			(fill
				(thermal_gap 0.5)
				(thermal_bridge_width 0.5)
				(island_removal_mode 0)
			)
			(polygon
				(pts
					(xy 347.5736 -9.0678) (xy 347.5736 -8.5598) (xy 347.9546 -8.5598) (xy 347.9546 -9.0678)
				)
			)
		)
		(zone
			(layer "B.Cu")
			(hatch none 0.5)
			(connect_pads
				(clearance 0)
			)
			(min_thickness 0.25)
			(keepout
				(tracks allowed)
				(vias not_allowed)
				(pads allowed)
				(copperpour not_allowed)
				(footprints allowed)
			)
			(placement
				(enabled no)
				(sheetname "")
			)
			(fill
				(thermal_gap 0.5)
				(thermal_bridge_width 0.5)
				(island_removal_mode 0)
			)
			(polygon
				(pts
					(xy 347.5736 -9.0678) (xy 347.5736 -8.5598) (xy 347.9546 -8.5598) (xy 347.9546 -9.0678)
				)
			)
		)
	)
	(footprint ""
		(layer "B.Cu")
		(at 168.0972 -7.366)
		(property "Reference" "R6U3"
			(at 0 0 0)
			(layer "B.SilkS")
			(hide yes)
			(effects
				(font
					(size 1.27 1.27)
				)
				(justify mirror)
			)
		)
		(property "Value" ""
			(at 0 0 0)
			(layer "B.Fab")
			(effects
				(font
					(size 1.27 1.27)
				)
				(justify mirror)
			)
		)
		(duplicate_pad_numbers_are_jumpers no)
		(fp_rect
			(start -0.2794 -0.1016)
			(end 0.2794 0.9906)
			(stroke
				(width 0)
				(type default)
			)
			(fill no)
			(layer "B.CrtYd")
		)
		(fp_line
			(start -0.2794 -0.1016)
			(end 0.2794 -0.1016)
			(stroke
				(width 0.1)
				(type default)
			)
			(layer "B.Fab")
		)
		(fp_line
			(start -0.2794 0.9906)
			(end -0.2794 -0.1016)
			(stroke
				(width 0.1)
				(type default)
			)
			(layer "B.Fab")
		)
		(fp_line
			(start 0.2794 -0.1016)
			(end 0.2794 0.9906)
			(stroke
				(width 0.1)
				(type default)
			)
			(layer "B.Fab")
		)
		(fp_line
			(start 0.2794 0.9906)
			(end -0.2794 0.9906)
			(stroke
				(width 0.1)
				(type default)
			)
			(layer "B.Fab")
		)
		(pad "1" smd rect
			(at 0 0 180)
			(size 0.508 0.508)
			(layers "B.Cu" "B.Mask" "B.Paste")
			(net "P3V3")
		)
		(pad "2" smd rect
			(at 0 0.889 180)
			(size 0.508 0.508)
			(layers "B.Cu" "B.Mask" "B.Paste")
			(net "FM_PVTT_GHJ_EN_R")
		)
		(zone
			(layer "B.Cu")
			(hatch none 0.5)
			(connect_pads
				(clearance 0)
			)
			(min_thickness 0.25)
			(keepout
				(tracks not_allowed)
				(vias allowed)
				(pads allowed)
				(copperpour not_allowed)
				(footprints allowed)
			)
			(placement
				(enabled no)
				(sheetname "")
			)
			(fill
				(thermal_gap 0.5)
				(thermal_bridge_width 0.5)
				(island_removal_mode 0)
			)
			(polygon
				(pts
					(xy 167.8432 -7.112) (xy 167.8432 -6.731) (xy 168.3512 -6.731) (xy 168.3512 -7.112)
				)
			)
		)
		(zone
			(layer "B.Cu")
			(hatch none 0.5)
			(connect_pads
				(clearance 0)
			)
			(min_thickness 0.25)
			(keepout
				(tracks allowed)
				(vias not_allowed)
				(pads allowed)
				(copperpour not_allowed)
				(footprints allowed)
			)
			(placement
				(enabled no)
				(sheetname "")
			)
			(fill
				(thermal_gap 0.5)
				(thermal_bridge_width 0.5)
				(island_removal_mode 0)
			)
			(polygon
				(pts
					(xy 167.8432 -7.112) (xy 167.8432 -6.731) (xy 168.3512 -6.731) (xy 168.3512 -7.112)
				)
			)
		)
	)
	(footprint ""
		(layer "B.Cu")
		(at 411.099 -142.0368 -90)
		(property "Reference" "C2L38"
			(at 0 0 90)
			(layer "B.SilkS")
			(hide yes)
			(effects
				(font
					(size 1.27 1.27)
				)
				(justify mirror)
			)
		)
		(property "Value" ""
			(at 0 0 90)
			(layer "B.Fab")
			(effects
				(font
					(size 1.27 1.27)
				)
				(justify mirror)
			)
		)
		(duplicate_pad_numbers_are_jumpers no)
		(fp_poly
			(pts
				(xy -0.3048 -0.1016) (xy -0.3048 0.9906) (xy 0.3048 0.9906) (xy 0.3048 -0.1016)
			)
			(stroke
				(width 0)
				(type default)
			)
			(fill no)
			(layer "B.CrtYd")
		)
		(fp_line
			(start -0.3048 0.9906)
			(end -0.3048 -0.1016)
			(stroke
				(width 0.1)
				(type default)
			)
			(layer "B.Fab")
		)
		(fp_line
			(start 0.3048 0.9906)
			(end -0.3048 0.9906)
			(stroke
				(width 0.1)
				(type default)
			)
			(layer "B.Fab")
		)
		(fp_line
			(start -0.3048 -0.1016)
			(end 0.3048 -0.1016)
			(stroke
				(width 0.1)
				(type default)
			)
			(layer "B.Fab")
		)
		(fp_line
			(start 0.3048 -0.1016)
			(end 0.3048 0.9906)
			(stroke
				(width 0.1)
				(type default)
			)
			(layer "B.Fab")
		)
		(pad "1" smd rect
			(at 0 0 90)
			(size 0.508 0.508)
			(layers "B.Cu" "B.Mask" "B.Paste")
			(net "SATA6G_P6_TX_C_DN")
		)
		(pad "2" smd rect
			(at 0 0.889 90)
			(size 0.508 0.508)
			(layers "B.Cu" "B.Mask" "B.Paste")
			(net "SATA6G_PCH_PCIE_UP_SATA_TXN<6>")
		)
		(zone
			(layer "B.Cu")
			(hatch none 0.5)
			(connect_pads
				(clearance 0)
			)
			(min_thickness 0.25)
			(keepout
				(tracks not_allowed)
				(vias allowed)
				(pads allowed)
				(copperpour not_allowed)
				(footprints allowed)
			)
			(placement
				(enabled no)
				(sheetname "")
			)
			(fill
				(thermal_gap 0.5)
				(thermal_bridge_width 0.5)
				(island_removal_mode 0)
			)
			(polygon
				(pts
					(xy 410.464 -141.7828) (xy 410.464 -142.2908) (xy 410.845 -142.2908) (xy 410.845 -141.7828)
				)
			)
		)
		(zone
			(layer "B.Cu")
			(hatch none 0.5)
			(connect_pads
				(clearance 0)
			)
			(min_thickness 0.25)
			(keepout
				(tracks allowed)
				(vias not_allowed)
				(pads allowed)
				(copperpour not_allowed)
				(footprints allowed)
			)
			(placement
				(enabled no)
				(sheetname "")
			)
			(fill
				(thermal_gap 0.5)
				(thermal_bridge_width 0.5)
				(island_removal_mode 0)
			)
			(polygon
				(pts
					(xy 410.845 -141.7828) (xy 410.845 -142.2908) (xy 410.464 -142.2908) (xy 410.464 -141.7828)
				)
			)
		)
	)
)
